(kicad_pcb
	(version 20260206)
	(generator "pcbnew")
	(generator_version "10.0")
	(general
		(thickness 1.6)
		(legacy_teardrops no)
	)
	(paper "A4")
	(title_block
		(title "04192023_DAF0TMB3IC0_F0TG_MB_C_brd_V02_OCP.brd")
		(comment 1 "Grand Teton / footprints 2055-2061 of 8354")
	)
	(layers
		(0 "F.Cu" signal "TOP")
		(4 "In1.Cu" signal "GND")
		(6 "In2.Cu" signal "IN1")
		(8 "In3.Cu" signal "GND1")
		(10 "In4.Cu" signal "IN2")
		(12 "In5.Cu" signal "GND2")
		(14 "In6.Cu" signal "IN3")
		(16 "In7.Cu" signal "GND3")
		(18 "In8.Cu" signal "VCC")
		(20 "In9.Cu" signal "VCC1")
		(22 "In10.Cu" signal "GND4")
		(24 "In11.Cu" signal "IN4")
		(26 "In12.Cu" signal "GND5")
		(28 "In13.Cu" signal "IN5")
		(30 "In14.Cu" signal "GND6")
		(32 "In15.Cu" signal "IN6")
		(34 "In16.Cu" signal "GND7")
		(2 "B.Cu" signal "BOTTOM")
		(9 "F.Adhes" user "F.Adhesive")
		(11 "B.Adhes" user "B.Adhesive")
		(13 "F.Paste" user "Package Geometry/Pastemask Top")
		(15 "B.Paste" user "Package Geometry/Pastemask Bottom")
		(5 "F.SilkS" user "Ref Des/Silkscreen Top")
		(7 "B.SilkS" user "Ref Des/Silkscreen Bottom")
		(1 "F.Mask" user "Board Geometry/Soldermask Top")
		(3 "B.Mask" user "Board Geometry/Soldermask Bottom")
		(17 "Dwgs.User" user "User.Drawings")
		(19 "Cmts.User" user "User.Comments")
		(21 "Eco1.User" user "User.Eco1")
		(23 "Eco2.User" user "User.Eco2")
		(25 "Edge.Cuts" user "Board Geometry/Outline")
		(27 "Margin" user)
		(31 "F.CrtYd" user "Package Geometry/Place Bound Top")
		(29 "B.CrtYd" user "Package Geometry/Place Bound Bottom")
		(35 "F.Fab" user "Ref Des/Assembly Top")
		(33 "B.Fab" user "Ref Des/Assembly Bottom")
	)
	(footprint ""
		(layer "F.Cu")
		(at 105.918 -426.466 90)
		(property "Reference" "R3460"
			(at 0 0 90)
			(layer "F.SilkS")
			(hide yes)
			(effects
				(font
					(size 1.27 1.27)
				)
			)
		)
		(property "Value" ""
			(at 0 0 90)
			(layer "F.Fab")
			(effects
				(font
					(size 1.27 1.27)
				)
			)
		)
		(duplicate_pad_numbers_are_jumpers no)
		(fp_line
			(start 0.7874 -0.4064)
			(end 0.7874 0.4064)
			(stroke
				(width 0.1524)
				(type default)
			)
			(layer "F.SilkS")
		)
		(fp_line
			(start -0.7874 -0.4064)
			(end 0.7874 -0.4064)
			(stroke
				(width 0.1524)
				(type default)
			)
			(layer "F.SilkS")
		)
		(fp_line
			(start 0.7874 0.4064)
			(end -0.7874 0.4064)
			(stroke
				(width 0.1524)
				(type default)
			)
			(layer "F.SilkS")
		)
		(fp_line
			(start -0.7874 0.4064)
			(end -0.7874 -0.4064)
			(stroke
				(width 0.1524)
				(type default)
			)
			(layer "F.SilkS")
		)
		(fp_line
			(start -0.12065 -0.305054)
			(end -0.12065 -0.2794)
			(stroke
				(width 0.1)
				(type default)
			)
			(layer "F.Fab")
		)
		(fp_line
			(start -0.67945 -0.305054)
			(end -0.12065 -0.305054)
			(stroke
				(width 0.1)
				(type default)
			)
			(layer "F.Fab")
		)
		(fp_line
			(start 0.67945 -0.3048)
			(end 0.67945 0.3048)
			(stroke
				(width 0.1)
				(type default)
			)
			(layer "F.Fab")
		)
		(fp_line
			(start 0.12065 -0.3048)
			(end 0.67945 -0.3048)
			(stroke
				(width 0.1)
				(type default)
			)
			(layer "F.Fab")
		)
		(fp_line
			(start 0.12065 -0.2794)
			(end 0.12065 -0.3048)
			(stroke
				(width 0.1)
				(type default)
			)
			(layer "F.Fab")
		)
		(fp_line
			(start -0.12065 -0.2794)
			(end 0.12065 -0.2794)
			(stroke
				(width 0.1)
				(type default)
			)
			(layer "F.Fab")
		)
		(fp_line
			(start 0.120396 0.2794)
			(end -0.12065 0.2794)
			(stroke
				(width 0.1)
				(type default)
			)
			(layer "F.Fab")
		)
		(fp_line
			(start -0.12065 0.2794)
			(end -0.12065 0.3048)
			(stroke
				(width 0.1)
				(type default)
			)
			(layer "F.Fab")
		)
		(fp_line
			(start 0.67945 0.3048)
			(end 0.120396 0.3048)
			(stroke
				(width 0.1)
				(type default)
			)
			(layer "F.Fab")
		)
		(fp_line
			(start 0.120396 0.3048)
			(end 0.120396 0.2794)
			(stroke
				(width 0.1)
				(type default)
			)
			(layer "F.Fab")
		)
		(fp_line
			(start -0.12065 0.3048)
			(end -0.67945 0.3048)
			(stroke
				(width 0.1)
				(type default)
			)
			(layer "F.Fab")
		)
		(fp_line
			(start -0.67945 0.3048)
			(end -0.67945 -0.305054)
			(stroke
				(width 0.1)
				(type default)
			)
			(layer "F.Fab")
		)
		(pad "1" smd circle
			(at -0.40005 0 90)
			(size 0 0)
			(layers "F.Cu" "F.Mask" "F.Paste")
			(net "GPU_NVS_PWR_BRAKE_N")
		)
		(pad "2" smd circle
			(at 0.40005 0 90)
			(size 0 0)
			(layers "F.Cu" "F.Mask" "F.Paste")
			(net "GND")
		)
	)
	(footprint ""
		(layer "F.Cu")
		(at 144.319244 -370.57203 -90)
		(property "Reference" "C767"
			(at 0 0 270)
			(layer "F.SilkS")
			(hide yes)
			(effects
				(font
					(size 1.27 1.27)
				)
			)
		)
		(property "Value" ""
			(at 0 0 270)
			(layer "F.Fab")
			(effects
				(font
					(size 1.27 1.27)
				)
			)
		)
		(duplicate_pad_numbers_are_jumpers no)
		(fp_line
			(start -0.299974 0.150114)
			(end -0.299974 -0.150114)
			(stroke
				(width 0.1)
				(type default)
			)
			(layer "F.Fab")
		)
		(fp_line
			(start 0.299974 0.150114)
			(end -0.299974 0.150114)
			(stroke
				(width 0.1)
				(type default)
			)
			(layer "F.Fab")
		)
		(fp_line
			(start -0.299974 -0.150114)
			(end 0.299974 -0.150114)
			(stroke
				(width 0.1)
				(type default)
			)
			(layer "F.Fab")
		)
		(fp_line
			(start 0.299974 -0.150114)
			(end 0.299974 0.150114)
			(stroke
				(width 0.1)
				(type default)
			)
			(layer "F.Fab")
		)
		(pad "1" smd rect
			(at -0.2667 0 270)
			(size 0.3048 0.381)
			(layers "F.Cu" "F.Mask" "F.Paste")
			(net "P5E_CPU1_P2_TX_C_DP<3>")
		)
		(pad "2" smd rect
			(at 0.2667 0 270)
			(size 0.3048 0.381)
			(layers "F.Cu" "F.Mask" "F.Paste")
			(net "P5E_CPU1_P2_TX_DP<3>")
		)
	)
	(footprint ""
		(layer "F.Cu")
		(at 438.455308 -405.788622 -90)
		(property "Reference" "PR6551"
			(at 0 0 270)
			(layer "F.SilkS")
			(hide yes)
			(effects
				(font
					(size 1.27 1.27)
				)
			)
		)
		(property "Value" ""
			(at 0 0 270)
			(layer "F.Fab")
			(effects
				(font
					(size 1.27 1.27)
				)
			)
		)
		(duplicate_pad_numbers_are_jumpers no)
		(fp_line
			(start -0.7874 0.4064)
			(end -0.7874 -0.4064)
			(stroke
				(width 0.1524)
				(type default)
			)
			(layer "F.SilkS")
		)
		(fp_line
			(start 0.7874 0.4064)
			(end -0.7874 0.4064)
			(stroke
				(width 0.1524)
				(type default)
			)
			(layer "F.SilkS")
		)
		(fp_line
			(start -0.7874 -0.4064)
			(end 0.7874 -0.4064)
			(stroke
				(width 0.1524)
				(type default)
			)
			(layer "F.SilkS")
		)
		(fp_line
			(start 0.7874 -0.4064)
			(end 0.7874 0.4064)
			(stroke
				(width 0.1524)
				(type default)
			)
			(layer "F.SilkS")
		)
		(fp_line
			(start -0.67945 0.3048)
			(end -0.67945 -0.305054)
			(stroke
				(width 0.1)
				(type default)
			)
			(layer "F.Fab")
		)
		(fp_line
			(start -0.12065 0.3048)
			(end -0.67945 0.3048)
			(stroke
				(width 0.1)
				(type default)
			)
			(layer "F.Fab")
		)
		(fp_line
			(start 0.120396 0.3048)
			(end 0.120396 0.2794)
			(stroke
				(width 0.1)
				(type default)
			)
			(layer "F.Fab")
		)
		(fp_line
			(start 0.67945 0.3048)
			(end 0.120396 0.3048)
			(stroke
				(width 0.1)
				(type default)
			)
			(layer "F.Fab")
		)
		(fp_line
			(start -0.12065 0.2794)
			(end -0.12065 0.3048)
			(stroke
				(width 0.1)
				(type default)
			)
			(layer "F.Fab")
		)
		(fp_line
			(start 0.120396 0.2794)
			(end -0.12065 0.2794)
			(stroke
				(width 0.1)
				(type default)
			)
			(layer "F.Fab")
		)
		(fp_line
			(start -0.12065 -0.2794)
			(end 0.12065 -0.2794)
			(stroke
				(width 0.1)
				(type default)
			)
			(layer "F.Fab")
		)
		(fp_line
			(start 0.12065 -0.2794)
			(end 0.12065 -0.3048)
			(stroke
				(width 0.1)
				(type default)
			)
			(layer "F.Fab")
		)
		(fp_line
			(start 0.12065 -0.3048)
			(end 0.67945 -0.3048)
			(stroke
				(width 0.1)
				(type default)
			)
			(layer "F.Fab")
		)
		(fp_line
			(start 0.67945 -0.3048)
			(end 0.67945 0.3048)
			(stroke
				(width 0.1)
				(type default)
			)
			(layer "F.Fab")
		)
		(fp_line
			(start -0.67945 -0.305054)
			(end -0.12065 -0.305054)
			(stroke
				(width 0.1)
				(type default)
			)
			(layer "F.Fab")
		)
		(fp_line
			(start -0.12065 -0.305054)
			(end -0.12065 -0.2794)
			(stroke
				(width 0.1)
				(type default)
			)
			(layer "F.Fab")
		)
		(pad "1" smd circle
			(at -0.40005 0 270)
			(size 0 0)
			(layers "F.Cu" "F.Mask" "F.Paste")
			(net "P3V3_AUX")
		)
		(pad "2" smd circle
			(at 0.40005 0 270)
			(size 0 0)
			(layers "F.Cu" "F.Mask" "F.Paste")
			(net "P0V9_RETIMER_CPU0_PVCC")
		)
	)
	(footprint ""
		(layer "F.Cu")
		(at 181.868064 -133.58495 -90)
		(property "Reference" "R159"
			(at 0 0 270)
			(layer "F.SilkS")
			(hide yes)
			(effects
				(font
					(size 1.27 1.27)
				)
			)
		)
		(property "Value" ""
			(at 0 0 270)
			(layer "F.Fab")
			(effects
				(font
					(size 1.27 1.27)
				)
			)
		)
		(duplicate_pad_numbers_are_jumpers no)
		(fp_line
			(start -0.7874 0.4064)
			(end -0.7874 -0.4064)
			(stroke
				(width 0.1524)
				(type default)
			)
			(layer "F.SilkS")
		)
		(fp_line
			(start 0.7874 0.4064)
			(end -0.7874 0.4064)
			(stroke
				(width 0.1524)
				(type default)
			)
			(layer "F.SilkS")
		)
		(fp_line
			(start -0.7874 -0.4064)
			(end 0.7874 -0.4064)
			(stroke
				(width 0.1524)
				(type default)
			)
			(layer "F.SilkS")
		)
		(fp_line
			(start 0.7874 -0.4064)
			(end 0.7874 0.4064)
			(stroke
				(width 0.1524)
				(type default)
			)
			(layer "F.SilkS")
		)
		(fp_line
			(start -0.67945 0.3048)
			(end -0.67945 -0.305054)
			(stroke
				(width 0.1)
				(type default)
			)
			(layer "F.Fab")
		)
		(fp_line
			(start -0.12065 0.3048)
			(end -0.67945 0.3048)
			(stroke
				(width 0.1)
				(type default)
			)
			(layer "F.Fab")
		)
		(fp_line
			(start 0.120396 0.3048)
			(end 0.120396 0.2794)
			(stroke
				(width 0.1)
				(type default)
			)
			(layer "F.Fab")
		)
		(fp_line
			(start 0.67945 0.3048)
			(end 0.120396 0.3048)
			(stroke
				(width 0.1)
				(type default)
			)
			(layer "F.Fab")
		)
		(fp_line
			(start -0.12065 0.2794)
			(end -0.12065 0.3048)
			(stroke
				(width 0.1)
				(type default)
			)
			(layer "F.Fab")
		)
		(fp_line
			(start 0.120396 0.2794)
			(end -0.12065 0.2794)
			(stroke
				(width 0.1)
				(type default)
			)
			(layer "F.Fab")
		)
		(fp_line
			(start -0.12065 -0.2794)
			(end 0.12065 -0.2794)
			(stroke
				(width 0.1)
				(type default)
			)
			(layer "F.Fab")
		)
		(fp_line
			(start 0.12065 -0.2794)
			(end 0.12065 -0.3048)
			(stroke
				(width 0.1)
				(type default)
			)
			(layer "F.Fab")
		)
		(fp_line
			(start 0.12065 -0.3048)
			(end 0.67945 -0.3048)
			(stroke
				(width 0.1)
				(type default)
			)
			(layer "F.Fab")
		)
		(fp_line
			(start 0.67945 -0.3048)
			(end 0.67945 0.3048)
			(stroke
				(width 0.1)
				(type default)
			)
			(layer "F.Fab")
		)
		(fp_line
			(start -0.67945 -0.305054)
			(end -0.12065 -0.305054)
			(stroke
				(width 0.1)
				(type default)
			)
			(layer "F.Fab")
		)
		(fp_line
			(start -0.12065 -0.305054)
			(end -0.12065 -0.2794)
			(stroke
				(width 0.1)
				(type default)
			)
			(layer "F.Fab")
		)
		(pad "1" smd circle
			(at -0.40005 0 270)
			(size 0 0)
			(layers "F.Cu" "F.Mask" "F.Paste")
			(net "CPU0_JTAG_BUF_OE")
		)
		(pad "2" smd circle
			(at 0.40005 0 270)
			(size 0 0)
			(layers "F.Cu" "F.Mask" "F.Paste")
			(net "CPU0_JTAG_BUF_R_OE")
		)
	)
	(footprint ""
		(layer "F.Cu")
		(at 442.077602 -420.10711)
		(property "Reference" "PC6540"
			(at 0 0 0)
			(layer "F.SilkS")
			(hide yes)
			(effects
				(font
					(size 1.27 1.27)
				)
			)
		)
		(property "Value" ""
			(at 0 0 0)
			(layer "F.Fab")
			(effects
				(font
					(size 1.27 1.27)
				)
			)
		)
		(duplicate_pad_numbers_are_jumpers no)
		(fp_line
			(start -0.7874 -0.4064)
			(end 0.7874 -0.4064)
			(stroke
				(width 0.1524)
				(type default)
			)
			(layer "F.SilkS")
		)
		(fp_line
			(start -0.7874 0.4064)
			(end -0.7874 -0.4064)
			(stroke
				(width 0.1524)
				(type default)
			)
			(layer "F.SilkS")
		)
		(fp_line
			(start 0.7874 -0.4064)
			(end 0.7874 0.4064)
			(stroke
				(width 0.1524)
				(type default)
			)
			(layer "F.SilkS")
		)
		(fp_line
			(start 0.7874 0.4064)
			(end -0.7874 0.4064)
			(stroke
				(width 0.1524)
				(type default)
			)
			(layer "F.SilkS")
		)
		(fp_line
			(start -0.67945 -0.305054)
			(end -0.12065 -0.305054)
			(stroke
				(width 0.1)
				(type default)
			)
			(layer "F.Fab")
		)
		(fp_line
			(start -0.67945 0.3048)
			(end -0.67945 -0.305054)
			(stroke
				(width 0.1)
				(type default)
			)
			(layer "F.Fab")
		)
		(fp_line
			(start -0.12065 -0.305054)
			(end -0.12065 -0.2794)
			(stroke
				(width 0.1)
				(type default)
			)
			(layer "F.Fab")
		)
		(fp_line
			(start -0.12065 -0.2794)
			(end 0.12065 -0.2794)
			(stroke
				(width 0.1)
				(type default)
			)
			(layer "F.Fab")
		)
		(fp_line
			(start -0.12065 0.2794)
			(end -0.12065 0.3048)
			(stroke
				(width 0.1)
				(type default)
			)
			(layer "F.Fab")
		)
		(fp_line
			(start -0.12065 0.3048)
			(end -0.67945 0.3048)
			(stroke
				(width 0.1)
				(type default)
			)
			(layer "F.Fab")
		)
		(fp_line
			(start 0.120396 0.2794)
			(end -0.12065 0.2794)
			(stroke
				(width 0.1)
				(type default)
			)
			(layer "F.Fab")
		)
		(fp_line
			(start 0.120396 0.3048)
			(end 0.120396 0.2794)
			(stroke
				(width 0.1)
				(type default)
			)
			(layer "F.Fab")
		)
		(fp_line
			(start 0.12065 -0.3048)
			(end 0.67945 -0.3048)
			(stroke
				(width 0.1)
				(type default)
			)
			(layer "F.Fab")
		)
		(fp_line
			(start 0.12065 -0.2794)
			(end 0.12065 -0.3048)
			(stroke
				(width 0.1)
				(type default)
			)
			(layer "F.Fab")
		)
		(fp_line
			(start 0.67945 -0.3048)
			(end 0.67945 0.3048)
			(stroke
				(width 0.1)
				(type default)
			)
			(layer "F.Fab")
		)
		(fp_line
			(start 0.67945 0.3048)
			(end 0.120396 0.3048)
			(stroke
				(width 0.1)
				(type default)
			)
			(layer "F.Fab")
		)
		(pad "1" smd circle
			(at -0.40005 0)
			(size 0 0)
			(layers "F.Cu" "F.Mask" "F.Paste")
			(net "P0V9_RETIMER_CPU0_SENSE_R_P")
		)
		(pad "2" smd circle
			(at 0.40005 0)
			(size 0 0)
			(layers "F.Cu" "F.Mask" "F.Paste")
			(net "P0V9_RETIMER_CPU0_SENSE_SH_N")
		)
	)
	(footprint ""
		(layer "F.Cu")
		(at 420.75735 -38.547548)
		(property "Reference" "R22"
			(at 0 0 0)
			(layer "F.SilkS")
			(hide yes)
			(effects
				(font
					(size 1.27 1.27)
				)
			)
		)
		(property "Value" ""
			(at 0 0 0)
			(layer "F.Fab")
			(effects
				(font
					(size 1.27 1.27)
				)
			)
		)
		(duplicate_pad_numbers_are_jumpers no)
		(fp_line
			(start -0.7874 -0.4064)
			(end 0.7874 -0.4064)
			(stroke
				(width 0.1524)
				(type default)
			)
			(layer "F.SilkS")
		)
		(fp_line
			(start -0.7874 0.4064)
			(end -0.7874 -0.4064)
			(stroke
				(width 0.1524)
				(type default)
			)
			(layer "F.SilkS")
		)
		(fp_line
			(start 0.7874 -0.4064)
			(end 0.7874 0.4064)
			(stroke
				(width 0.1524)
				(type default)
			)
			(layer "F.SilkS")
		)
		(fp_line
			(start 0.7874 0.4064)
			(end -0.7874 0.4064)
			(stroke
				(width 0.1524)
				(type default)
			)
			(layer "F.SilkS")
		)
		(fp_line
			(start -0.67945 -0.305054)
			(end -0.12065 -0.305054)
			(stroke
				(width 0.1)
				(type default)
			)
			(layer "F.Fab")
		)
		(fp_line
			(start -0.67945 0.3048)
			(end -0.67945 -0.305054)
			(stroke
				(width 0.1)
				(type default)
			)
			(layer "F.Fab")
		)
		(fp_line
			(start -0.12065 -0.305054)
			(end -0.12065 -0.2794)
			(stroke
				(width 0.1)
				(type default)
			)
			(layer "F.Fab")
		)
		(fp_line
			(start -0.12065 -0.2794)
			(end 0.12065 -0.2794)
			(stroke
				(width 0.1)
				(type default)
			)
			(layer "F.Fab")
		)
		(fp_line
			(start -0.12065 0.2794)
			(end -0.12065 0.3048)
			(stroke
				(width 0.1)
				(type default)
			)
			(layer "F.Fab")
		)
		(fp_line
			(start -0.12065 0.3048)
			(end -0.67945 0.3048)
			(stroke
				(width 0.1)
				(type default)
			)
			(layer "F.Fab")
		)
		(fp_line
			(start 0.120396 0.2794)
			(end -0.12065 0.2794)
			(stroke
				(width 0.1)
				(type default)
			)
			(layer "F.Fab")
		)
		(fp_line
			(start 0.120396 0.3048)
			(end 0.120396 0.2794)
			(stroke
				(width 0.1)
				(type default)
			)
			(layer "F.Fab")
		)
		(fp_line
			(start 0.12065 -0.3048)
			(end 0.67945 -0.3048)
			(stroke
				(width 0.1)
				(type default)
			)
			(layer "F.Fab")
		)
		(fp_line
			(start 0.12065 -0.2794)
			(end 0.12065 -0.3048)
			(stroke
				(width 0.1)
				(type default)
			)
			(layer "F.Fab")
		)
		(fp_line
			(start 0.67945 -0.3048)
			(end 0.67945 0.3048)
			(stroke
				(width 0.1)
				(type default)
			)
			(layer "F.Fab")
		)
		(fp_line
			(start 0.67945 0.3048)
			(end 0.120396 0.3048)
			(stroke
				(width 0.1)
				(type default)
			)
			(layer "F.Fab")
		)
		(pad "1" smd circle
			(at -0.40005 0)
			(size 0 0)
			(layers "F.Cu" "F.Mask" "F.Paste")
			(net "P1V8_AUX")
		)
		(pad "2" smd circle
			(at 0.40005 0)
			(size 0 0)
			(layers "F.Cu" "F.Mask" "F.Paste")
			(net "PU_BIOS_USB_RECOVERY")
		)
	)
	(footprint ""
		(layer "F.Cu")
		(at 162.162744 -344.153998 -90)
		(property "Reference" "PR406"
			(at 0 0 270)
			(layer "F.SilkS")
			(hide yes)
			(effects
				(font
					(size 1.27 1.27)
				)
			)
		)
		(property "Value" ""
			(at 0 0 270)
			(layer "F.Fab")
			(effects
				(font
					(size 1.27 1.27)
				)
			)
		)
		(duplicate_pad_numbers_are_jumpers no)
		(fp_line
			(start -0.7874 0.4064)
			(end -0.7874 -0.4064)
			(stroke
				(width 0.1524)
				(type default)
			)
			(layer "F.SilkS")
		)
		(fp_line
			(start 0.7874 0.4064)
			(end -0.7874 0.4064)
			(stroke
				(width 0.1524)
				(type default)
			)
			(layer "F.SilkS")
		)
		(fp_line
			(start -0.7874 -0.4064)
			(end 0.7874 -0.4064)
			(stroke
				(width 0.1524)
				(type default)
			)
			(layer "F.SilkS")
		)
		(fp_line
			(start 0.7874 -0.4064)
			(end 0.7874 0.4064)
			(stroke
				(width 0.1524)
				(type default)
			)
			(layer "F.SilkS")
		)
		(fp_line
			(start -0.67945 0.3048)
			(end -0.67945 -0.305054)
			(stroke
				(width 0.1)
				(type default)
			)
			(layer "F.Fab")
		)
		(fp_line
			(start -0.12065 0.3048)
			(end -0.67945 0.3048)
			(stroke
				(width 0.1)
				(type default)
			)
			(layer "F.Fab")
		)
		(fp_line
			(start 0.120396 0.3048)
			(end 0.120396 0.2794)
			(stroke
				(width 0.1)
				(type default)
			)
			(layer "F.Fab")
		)
		(fp_line
			(start 0.67945 0.3048)
			(end 0.120396 0.3048)
			(stroke
				(width 0.1)
				(type default)
			)
			(layer "F.Fab")
		)
		(fp_line
			(start -0.12065 0.2794)
			(end -0.12065 0.3048)
			(stroke
				(width 0.1)
				(type default)
			)
			(layer "F.Fab")
		)
		(fp_line
			(start 0.120396 0.2794)
			(end -0.12065 0.2794)
			(stroke
				(width 0.1)
				(type default)
			)
			(layer "F.Fab")
		)
		(fp_line
			(start -0.12065 -0.2794)
			(end 0.12065 -0.2794)
			(stroke
				(width 0.1)
				(type default)
			)
			(layer "F.Fab")
		)
		(fp_line
			(start 0.12065 -0.2794)
			(end 0.12065 -0.3048)
			(stroke
				(width 0.1)
				(type default)
			)
			(layer "F.Fab")
		)
		(fp_line
			(start 0.12065 -0.3048)
			(end 0.67945 -0.3048)
			(stroke
				(width 0.1)
				(type default)
			)
			(layer "F.Fab")
		)
		(fp_line
			(start 0.67945 -0.3048)
			(end 0.67945 0.3048)
			(stroke
				(width 0.1)
				(type default)
			)
			(layer "F.Fab")
		)
		(fp_line
			(start -0.67945 -0.305054)
			(end -0.12065 -0.305054)
			(stroke
				(width 0.1)
				(type default)
			)
			(layer "F.Fab")
		)
		(fp_line
			(start -0.12065 -0.305054)
			(end -0.12065 -0.2794)
			(stroke
				(width 0.1)
				(type default)
			)
			(layer "F.Fab")
		)
		(pad "1" smd circle
			(at -0.40005 0 270)
			(size 0 0)
			(layers "F.Cu" "F.Mask" "F.Paste")
			(net "NC_PVDD11_S3_P1_IMON3")
		)
		(pad "2" smd circle
			(at 0.40005 0 270)
			(size 0 0)
			(layers "F.Cu" "F.Mask" "F.Paste")
			(net "GND")
		)
	)
)
